(kicad_pcb
	(version 20260206)
	(generator "pcbnew")
	(generator_version "10.0")
	(general
		(thickness 1.6)
		(legacy_teardrops no)
	)
	(paper "A4")
	(title_block
		(title "Wiwynn_Tioga_Pass_MB.brd")
		(comment 1 "Tioga Pass / footprints 1856-1860 of 4770")
	)
	(layers
		(0 "F.Cu" signal "TOP")
		(4 "In1.Cu" signal "L2GND")
		(6 "In2.Cu" signal "L3")
		(8 "In3.Cu" signal "L4GND")
		(10 "In4.Cu" signal "L5")
		(12 "In5.Cu" signal "L6GND")
		(14 "In6.Cu" signal "L7VCC")
		(16 "In7.Cu" signal "L8VCC")
		(18 "In8.Cu" signal "L9GND")
		(20 "In9.Cu" signal "L10")
		(22 "In10.Cu" signal "L11GND")
		(24 "In11.Cu" signal "L12")
		(26 "In12.Cu" signal "L13GND")
		(2 "B.Cu" signal "BOTTOM")
		(9 "F.Adhes" user "F.Adhesive")
		(11 "B.Adhes" user "B.Adhesive")
		(13 "F.Paste" user "Package Geometry/Pastemask Top")
		(15 "B.Paste" user "Package Geometry/Pastemask Bottom")
		(5 "F.SilkS" user "Ref Des/Silkscreen Top")
		(7 "B.SilkS" user "Ref Des/Silkscreen Bottom")
		(1 "F.Mask" user "Board Geometry/Soldermask Top")
		(3 "B.Mask" user "Board Geometry/Soldermask Bottom")
		(17 "Dwgs.User" user "User.Drawings")
		(19 "Cmts.User" user "User.Comments")
		(21 "Eco1.User" user "User.Eco1")
		(23 "Eco2.User" user "User.Eco2")
		(25 "Edge.Cuts" user "Board Geometry/Outline")
		(27 "Margin" user)
		(31 "F.CrtYd" user "Package Geometry/Place Bound Top")
		(29 "B.CrtYd" user "Package Geometry/Place Bound Bottom")
		(35 "F.Fab" user "Ref Des/Assembly Top")
		(33 "B.Fab" user "Ref Des/Assembly Bottom")
	)
	(footprint ""
		(layer "F.Cu")
		(at 412.4325 -110.617 90)
		(property "Reference" "R2R5"
			(at 0 0 90)
			(layer "F.SilkS")
			(hide yes)
			(effects
				(font
					(size 1.27 1.27)
				)
			)
		)
		(property "Value" ""
			(at 0 0 90)
			(layer "F.Fab")
			(effects
				(font
					(size 1.27 1.27)
				)
			)
		)
		(duplicate_pad_numbers_are_jumpers no)
		(fp_poly
			(pts
				(xy -0.2794 -0.1016) (xy 0.2794 -0.1016) (xy 0.2794 0.9906) (xy -0.2794 0.9906)
			)
			(stroke
				(width 0)
				(type default)
			)
			(fill no)
			(layer "F.CrtYd")
		)
		(fp_line
			(start 0.2794 -0.1016)
			(end -0.2794 -0.1016)
			(stroke
				(width 0.1)
				(type default)
			)
			(layer "F.Fab")
		)
		(fp_line
			(start -0.2794 -0.1016)
			(end -0.2794 0.9906)
			(stroke
				(width 0.1)
				(type default)
			)
			(layer "F.Fab")
		)
		(fp_line
			(start 0.2794 0.9906)
			(end 0.2794 -0.1016)
			(stroke
				(width 0.1)
				(type default)
			)
			(layer "F.Fab")
		)
		(fp_line
			(start -0.2794 0.9906)
			(end 0.2794 0.9906)
			(stroke
				(width 0.1)
				(type default)
			)
			(layer "F.Fab")
		)
		(pad "1" smd rect
			(at 0 0 90)
			(size 0.508 0.508)
			(layers "F.Cu" "F.Mask" "F.Paste")
			(net "P3V3_STBY")
		)
		(pad "2" smd rect
			(at 0 0.889 90)
			(size 0.508 0.508)
			(layers "F.Cu" "F.Mask" "F.Paste")
			(net "FM_PCH_PLD_DATA")
		)
		(zone
			(layer "F.Cu")
			(hatch none 0.5)
			(connect_pads
				(clearance 0)
			)
			(min_thickness 0.25)
			(keepout
				(tracks allowed)
				(vias not_allowed)
				(pads allowed)
				(copperpour not_allowed)
				(footprints allowed)
			)
			(placement
				(enabled no)
				(sheetname "")
			)
			(fill
				(thermal_gap 0.5)
				(thermal_bridge_width 0.5)
				(island_removal_mode 0)
			)
			(polygon
				(pts
					(xy 412.6865 -110.363) (xy 412.6865 -110.871) (xy 413.0675 -110.871) (xy 413.0675 -110.363)
				)
			)
		)
		(zone
			(layer "F.Cu")
			(hatch none 0.5)
			(connect_pads
				(clearance 0)
			)
			(min_thickness 0.25)
			(keepout
				(tracks not_allowed)
				(vias allowed)
				(pads allowed)
				(copperpour not_allowed)
				(footprints allowed)
			)
			(placement
				(enabled no)
				(sheetname "")
			)
			(fill
				(thermal_gap 0.5)
				(thermal_bridge_width 0.5)
				(island_removal_mode 0)
			)
			(polygon
				(pts
					(xy 413.0675 -110.363) (xy 413.0675 -110.871) (xy 412.6865 -110.871) (xy 412.6865 -110.363)
				)
			)
		)
	)
	(footprint ""
		(layer "F.Cu")
		(at 1.84912 -142.002256 90)
		(property "Reference" "C1A10"
			(at 0 0 90)
			(layer "F.SilkS")
			(hide yes)
			(effects
				(font
					(size 1.27 1.27)
				)
			)
		)
		(property "Value" ""
			(at 0 0 90)
			(layer "F.Fab")
			(effects
				(font
					(size 1.27 1.27)
				)
			)
		)
		(duplicate_pad_numbers_are_jumpers no)
		(fp_rect
			(start 0.3048 -0.1016)
			(end -0.3048 0.9906)
			(stroke
				(width 0)
				(type default)
			)
			(fill no)
			(layer "F.CrtYd")
		)
		(fp_line
			(start 0.3048 -0.1016)
			(end -0.3048 -0.1016)
			(stroke
				(width 0.1)
				(type default)
			)
			(layer "F.Fab")
		)
		(fp_line
			(start -0.3048 -0.1016)
			(end -0.3048 0.9906)
			(stroke
				(width 0.1)
				(type default)
			)
			(layer "F.Fab")
		)
		(fp_line
			(start 0.3048 0.9906)
			(end 0.3048 -0.1016)
			(stroke
				(width 0.1)
				(type default)
			)
			(layer "F.Fab")
		)
		(fp_line
			(start -0.3048 0.9906)
			(end 0.3048 0.9906)
			(stroke
				(width 0.1)
				(type default)
			)
			(layer "F.Fab")
		)
		(pad "1" smd rect
			(at 0 0 90)
			(size 0.508 0.508)
			(layers "F.Cu" "F.Mask" "F.Paste")
			(net "VR_FET_SW_P12V_STBY_PVDDQ_KLM")
		)
		(pad "2" smd rect
			(at 0 0.889 90)
			(size 0.508 0.508)
			(layers "F.Cu" "F.Mask" "F.Paste")
			(net "GND")
		)
		(zone
			(layer "F.Cu")
			(hatch none 0.5)
			(connect_pads
				(clearance 0)
			)
			(min_thickness 0.25)
			(keepout
				(tracks not_allowed)
				(vias allowed)
				(pads allowed)
				(copperpour not_allowed)
				(footprints allowed)
			)
			(placement
				(enabled no)
				(sheetname "")
			)
			(fill
				(thermal_gap 0.5)
				(thermal_bridge_width 0.5)
				(island_removal_mode 0)
			)
			(polygon
				(pts
					(xy 2.10312 -142.256256) (xy 2.10312 -141.748256) (xy 2.48412 -141.748256) (xy 2.48412 -142.256256)
				)
			)
		)
		(zone
			(layer "F.Cu")
			(hatch none 0.5)
			(connect_pads
				(clearance 0)
			)
			(min_thickness 0.25)
			(keepout
				(tracks allowed)
				(vias not_allowed)
				(pads allowed)
				(copperpour not_allowed)
				(footprints allowed)
			)
			(placement
				(enabled no)
				(sheetname "")
			)
			(fill
				(thermal_gap 0.5)
				(thermal_bridge_width 0.5)
				(island_removal_mode 0)
			)
			(polygon
				(pts
					(xy 2.10312 -142.256256) (xy 2.10312 -141.748256) (xy 2.48412 -141.748256) (xy 2.48412 -142.256256)
				)
			)
		)
	)
	(footprint ""
		(layer "F.Cu")
		(at 432.689762 3.81 90)
		(property "Reference" "J8G2"
			(at 3.96621 6.19506 0)
			(unlocked yes)
			(layer "B.SilkS")
			(effects
				(font
					(size 0.7874 0.5842)
					(thickness 0.1524)
				)
				(justify mirror)
			)
		)
		(property "Value" ""
			(at 0 0 90)
			(layer "F.Fab")
			(effects
				(font
					(size 1.27 1.27)
				)
			)
		)
		(duplicate_pad_numbers_are_jumpers no)
		(fp_line
			(start 3.8227 -1.27)
			(end 3.8227 13.97)
			(stroke
				(width 0.1524)
				(type default)
			)
			(layer "F.SilkS")
		)
		(fp_line
			(start -1.2827 -1.27)
			(end 3.8227 -1.27)
			(stroke
				(width 0.1524)
				(type default)
			)
			(layer "F.SilkS")
		)
		(fp_line
			(start 3.7592 -1.143)
			(end 3.758184 -1.143)
			(stroke
				(width 0.1)
				(type default)
			)
			(layer "F.SilkS")
		)
		(fp_line
			(start -1.2192 -1.143)
			(end -1.218946 -1.143)
			(stroke
				(width 0.1)
				(type default)
			)
			(layer "F.SilkS")
		)
		(fp_line
			(start 3.7592 13.843)
			(end 3.758946 13.843)
			(stroke
				(width 0.1524)
				(type default)
			)
			(layer "F.SilkS")
		)
		(fp_line
			(start -1.2192 13.843)
			(end -1.218946 13.843)
			(stroke
				(width 0.1524)
				(type default)
			)
			(layer "F.SilkS")
		)
		(fp_line
			(start 3.8227 13.97)
			(end -1.2827 13.97)
			(stroke
				(width 0.1524)
				(type default)
			)
			(layer "F.SilkS")
		)
		(fp_line
			(start -1.2827 13.97)
			(end -1.2827 -1.27)
			(stroke
				(width 0.1524)
				(type default)
			)
			(layer "F.SilkS")
		)
		(fp_poly
			(pts
				(xy -1.7145 -0.005588) (xy -2.9845 0.502412) (xy -2.9845 -0.513588)
			)
			(stroke
				(width 0)
				(type default)
			)
			(fill yes)
			(layer "F.SilkS")
		)
		(fp_poly
			(pts
				(xy -1.7145 -0.005588) (xy -2.9845 0.502412) (xy -2.9845 -0.513588)
			)
			(stroke
				(width 0)
				(type default)
			)
			(fill yes)
			(layer "B.SilkS")
		)
		(fp_poly
			(pts
				(xy -1.2827 -1.27) (xy -1.2827 13.97) (xy 3.8227 13.97) (xy 3.8227 -1.27)
			)
			(stroke
				(width 0)
				(type default)
			)
			(fill no)
			(layer "F.CrtYd")
		)
		(fp_poly
			(pts
				(xy -1.7145 -0.005588) (xy -2.9845 0.502412) (xy -2.9845 -0.513588)
			)
			(stroke
				(width 0)
				(type default)
			)
			(fill yes)
			(layer "B.Fab")
		)
		(fp_line
			(start 3.8227 -1.27)
			(end -1.2827 -1.27)
			(stroke
				(width 0.1)
				(type default)
			)
			(layer "F.Fab")
		)
		(fp_line
			(start -1.2827 -1.27)
			(end -1.2827 13.97)
			(stroke
				(width 0.1)
				(type default)
			)
			(layer "F.Fab")
		)
		(fp_line
			(start 3.8227 13.97)
			(end 3.8227 -1.27)
			(stroke
				(width 0.1)
				(type default)
			)
			(layer "F.Fab")
		)
		(fp_line
			(start -1.2827 13.97)
			(end 3.8227 13.97)
			(stroke
				(width 0.1)
				(type default)
			)
			(layer "F.Fab")
		)
		(fp_poly
			(pts
				(xy -1.7145 -0.005588) (xy -2.9845 0.502412) (xy -2.9845 -0.513588)
			)
			(stroke
				(width 0)
				(type default)
			)
			(fill yes)
			(layer "F.Fab")
		)
		(fp_text user "2"
			(at 4.470908 -0.198882 0)
			(unlocked yes)
			(layer "F.SilkS")
			(effects
				(font
					(size 0.7874 0.5842)
					(thickness 0.1524)
				)
			)
		)
		(fp_text user "12"
			(at 4.1402 14.630908 90)
			(unlocked yes)
			(layer "F.SilkS")
			(effects
				(font
					(size 0.7874 0.5842)
					(thickness 0.1524)
				)
			)
		)
		(fp_text user "11"
			(at -0.870204 14.70787 0)
			(unlocked yes)
			(layer "F.SilkS")
			(effects
				(font
					(size 0.7874 0.5842)
					(thickness 0.1524)
				)
			)
		)
		(fp_text user "2"
			(at 4.5466 0.02667 90)
			(unlocked yes)
			(layer "B.SilkS")
			(effects
				(font
					(size 0.7874 0.5842)
					(thickness 0.1524)
				)
				(justify mirror)
			)
		)
		(fp_text user "12"
			(at 4.9403 12.72667 90)
			(unlocked yes)
			(layer "B.SilkS")
			(effects
				(font
					(size 0.7874 0.5842)
					(thickness 0.1524)
				)
				(justify mirror)
			)
		)
		(fp_text user "11"
			(at -2.2606 12.72667 90)
			(unlocked yes)
			(layer "B.SilkS")
			(effects
				(font
					(size 0.7874 0.5842)
					(thickness 0.1524)
				)
				(justify mirror)
			)
		)
		(fp_text user "2"
			(at 4.5466 0.02667 90)
			(unlocked yes)
			(layer "B.Fab")
			(effects
				(font
					(size 0.7874 0.5842)
					(thickness 0.1524)
				)
				(justify mirror)
			)
		)
		(fp_text user "12"
			(at 4.9403 12.72667 90)
			(unlocked yes)
			(layer "B.Fab")
			(effects
				(font
					(size 0.7874 0.5842)
					(thickness 0.1524)
				)
				(justify mirror)
			)
		)
		(fp_text user "11"
			(at -2.2606 12.72667 90)
			(unlocked yes)
			(layer "B.Fab")
			(effects
				(font
					(size 0.7874 0.5842)
					(thickness 0.1524)
				)
				(justify mirror)
			)
		)
		(fp_text user "2"
			(at 4.445 0.669544 90)
			(unlocked yes)
			(layer "F.Fab")
			(effects
				(font
					(size 0.7874 0.5842)
					(thickness 0.1524)
				)
			)
		)
		(fp_text user "11"
			(at -1.4478 13.66647 90)
			(unlocked yes)
			(layer "F.Fab")
			(effects
				(font
					(size 0.7874 0.5842)
					(thickness 0.1524)
				)
			)
		)
		(fp_text user "12"
			(at 0.889 14.639544 90)
			(unlocked yes)
			(layer "F.Fab")
			(effects
				(font
					(size 0.7874 0.5842)
					(thickness 0.1524)
				)
			)
		)
		(pad "1" thru_hole rect
			(at 0 0 90)
			(size 1.6256 1.6256)
			(drill 1.2446)
			(layers "*.Cu" "*.Mask")
			(remove_unused_layers no)
			(net "TP_JUMPER_BLOCK_1_1")
			(clearance 0.127)
			(thermal_gap 0.127)
			(padstack
				(mode front_inner_back)
				(layer "Inner"
					(shape circle)
					(size 1.6256 1.6256)
					(clearance 0.127)
				)
				(layer "B.Cu"
					(shape rect)
					(size 1.6256 1.6256)
					(clearance 0.127)
				)
			)
		)
		(pad "2" thru_hole circle
			(at 2.54 0 90)
			(size 1.6256 1.6256)
			(drill 1.2446)
			(layers "*.Cu" "*.Mask")
			(remove_unused_layers no)
			(net "TP_JUMPER_BLOCK_1_2")
			(clearance 0.127)
			(thermal_gap 0.127)
		)
		(pad "3" thru_hole circle
			(at 0 2.54 90)
			(size 1.6256 1.6256)
			(drill 1.2446)
			(layers "*.Cu" "*.Mask")
			(remove_unused_layers no)
			(net "RST_BMC_SRST_N")
			(clearance 0.127)
			(thermal_gap 0.127)
		)
		(pad "4" thru_hole circle
			(at 2.54 2.54 90)
			(size 1.6256 1.6256)
			(drill 1.2446)
			(layers "*.Cu" "*.Mask")
			(remove_unused_layers no)
			(net "FM_IE_DISABLE_N")
			(clearance 0.127)
			(thermal_gap 0.127)
		)
		(pad "5" thru_hole circle
			(at 0 5.08 90)
			(size 1.6256 1.6256)
			(drill 1.2446)
			(layers "*.Cu" "*.Mask")
			(remove_unused_layers no)
			(net "GND")
			(clearance 0.127)
			(thermal_gap 0.127)
		)
		(pad "6" thru_hole circle
			(at 2.54 5.08 90)
			(size 1.6256 1.6256)
			(drill 1.2446)
			(layers "*.Cu" "*.Mask")
			(remove_unused_layers no)
			(net "GND")
			(clearance 0.127)
			(thermal_gap 0.127)
		)
		(pad "7" thru_hole circle
			(at 0 7.62 90)
			(size 1.6256 1.6256)
			(drill 1.2446)
			(layers "*.Cu" "*.Mask")
			(remove_unused_layers no)
			(net "TP_JUMPER_BLOCK_1_7")
			(clearance 0.127)
			(thermal_gap 0.127)
		)
		(pad "8" thru_hole circle
			(at 2.54 7.62 90)
			(size 1.6256 1.6256)
			(drill 1.2446)
			(layers "*.Cu" "*.Mask")
			(remove_unused_layers no)
			(net "TP_JUMPER_BLOCK_1_8")
			(clearance 0.127)
			(thermal_gap 0.127)
		)
		(pad "9" thru_hole circle
			(at 0 10.16 90)
			(size 1.6256 1.6256)
			(drill 1.2446)
			(layers "*.Cu" "*.Mask")
			(remove_unused_layers no)
			(net "FM_CPLD_UART_CH_LOCK_N")
			(clearance 0.127)
			(thermal_gap 0.127)
		)
		(pad "10" thru_hole circle
			(at 2.54 10.16 90)
			(size 1.6256 1.6256)
			(drill 1.2446)
			(layers "*.Cu" "*.Mask")
			(remove_unused_layers no)
			(net "FM_DIS_ADR_DLY")
			(clearance 0.127)
			(thermal_gap 0.127)
		)
		(pad "11" thru_hole circle
			(at 0 12.7 90)
			(size 1.6256 1.6256)
			(drill 1.2446)
			(layers "*.Cu" "*.Mask")
			(remove_unused_layers no)
			(net "GND")
			(clearance 0.127)
			(thermal_gap 0.127)
		)
		(pad "12" thru_hole circle
			(at 2.54 12.7 90)
			(size 1.6256 1.6256)
			(drill 1.2446)
			(layers "*.Cu" "*.Mask")
			(remove_unused_layers no)
			(net "GND")
			(clearance 0.127)
			(thermal_gap 0.127)
		)
	)
	(footprint ""
		(layer "F.Cu")
		(at 83.856068 -140.208 -90)
		(property "Reference" "C2A10"
			(at 1.848866 0.752348 270)
			(unlocked yes)
			(layer "F.SilkS")
			(effects
				(font
					(size 1.27 0.9652)
					(thickness 0.1524)
				)
			)
		)
		(property "Value" ""
			(at 0 0 270)
			(layer "F.Fab")
			(effects
				(font
					(size 1.27 1.27)
				)
			)
		)
		(duplicate_pad_numbers_are_jumpers no)
		(fp_rect
			(start -0.500126 1.598422)
			(end 0.500126 -0.201422)
			(stroke
				(width 0)
				(type default)
			)
			(fill no)
			(layer "F.CrtYd")
		)
		(fp_line
			(start -0.500126 1.598422)
			(end -0.500126 -0.201422)
			(stroke
				(width 0.1)
				(type default)
			)
			(layer "F.Fab")
		)
		(fp_line
			(start 0.500126 1.598422)
			(end -0.500126 1.598422)
			(stroke
				(width 0.1)
				(type default)
			)
			(layer "F.Fab")
		)
		(fp_line
			(start -0.500126 -0.201422)
			(end 0.500126 -0.201422)
			(stroke
				(width 0.1)
				(type default)
			)
			(layer "F.Fab")
		)
		(fp_line
			(start 0.500126 -0.201422)
			(end 0.500126 1.598422)
			(stroke
				(width 0.1)
				(type default)
			)
			(layer "F.Fab")
		)
		(pad "1" smd rect
			(at 0 0 180)
			(size 0.889 0.9906)
			(layers "F.Cu" "F.Mask" "F.Paste")
			(net "PVDDQ_KLM")
		)
		(pad "2" smd rect
			(at 0 1.397 180)
			(size 0.889 0.9906)
			(layers "F.Cu" "F.Mask" "F.Paste")
			(net "GND")
		)
		(zone
			(layer "F.Cu")
			(hatch none 0.5)
			(connect_pads
				(clearance 0)
			)
			(min_thickness 0.25)
			(keepout
				(tracks not_allowed)
				(vias allowed)
				(pads allowed)
				(copperpour not_allowed)
				(footprints allowed)
			)
			(placement
				(enabled no)
				(sheetname "")
			)
			(fill
				(thermal_gap 0.5)
				(thermal_bridge_width 0.5)
				(island_removal_mode 0)
			)
			(polygon
				(pts
					(xy 82.903568 -140.7033) (xy 82.903568 -139.7127) (xy 83.411568 -139.7127) (xy 83.411568 -140.7033)
				)
			)
		)
		(zone
			(layer "F.Cu")
			(hatch none 0.5)
			(connect_pads
				(clearance 0)
			)
			(min_thickness 0.25)
			(keepout
				(tracks allowed)
				(vias not_allowed)
				(pads allowed)
				(copperpour not_allowed)
				(footprints allowed)
			)
			(placement
				(enabled no)
				(sheetname "")
			)
			(fill
				(thermal_gap 0.5)
				(thermal_bridge_width 0.5)
				(island_removal_mode 0)
			)
			(polygon
				(pts
					(xy 82.903568 -140.7033) (xy 82.903568 -139.7127) (xy 83.411568 -139.7127) (xy 83.411568 -140.7033)
				)
			)
		)
	)
	(footprint ""
		(layer "F.Cu")
		(at 191.897 -23.396194)
		(property "Reference" "C4F9"
			(at 0 0 0)
			(layer "F.SilkS")
			(hide yes)
			(effects
				(font
					(size 1.27 1.27)
				)
			)
		)
		(property "Value" ""
			(at 0 0 0)
			(layer "F.Fab")
			(effects
				(font
					(size 1.27 1.27)
				)
			)
		)
		(duplicate_pad_numbers_are_jumpers no)
		(fp_poly
			(pts
				(xy 0.3048 -0.1016) (xy 0.3048 0.9906) (xy -0.3048 0.9906) (xy -0.3048 -0.1016)
			)
			(stroke
				(width 0)
				(type default)
			)
			(fill no)
			(layer "F.CrtYd")
		)
		(fp_line
			(start -0.3048 -0.1016)
			(end -0.3048 0.9906)
			(stroke
				(width 0.1)
				(type default)
			)
			(layer "F.Fab")
		)
		(fp_line
			(start -0.3048 0.9906)
			(end 0.3048 0.9906)
			(stroke
				(width 0.1)
				(type default)
			)
			(layer "F.Fab")
		)
		(fp_line
			(start 0.3048 -0.1016)
			(end -0.3048 -0.1016)
			(stroke
				(width 0.1)
				(type default)
			)
			(layer "F.Fab")
		)
		(fp_line
			(start 0.3048 0.9906)
			(end 0.3048 -0.1016)
			(stroke
				(width 0.1)
				(type default)
			)
			(layer "F.Fab")
		)
		(pad "1" smd rect
			(at 0 0)
			(size 0.508 0.508)
			(layers "F.Cu" "F.Mask" "F.Paste")
			(net "M_A_CPU_VREF")
		)
		(pad "2" smd rect
			(at 0 0.889)
			(size 0.508 0.508)
			(layers "F.Cu" "F.Mask" "F.Paste")
			(net "GND")
		)
		(zone
			(layer "F.Cu")
			(hatch none 0.5)
			(connect_pads
				(clearance 0)
			)
			(min_thickness 0.25)
			(keepout
				(tracks allowed)
				(vias not_allowed)
				(pads allowed)
				(copperpour not_allowed)
				(footprints allowed)
			)
			(placement
				(enabled no)
				(sheetname "")
			)
			(fill
				(thermal_gap 0.5)
				(thermal_bridge_width 0.5)
				(island_removal_mode 0)
			)
			(polygon
				(pts
					(xy 191.643 -23.142194) (xy 192.151 -23.142194) (xy 192.151 -22.761194) (xy 191.643 -22.761194)
				)
			)
		)
		(zone
			(layer "F.Cu")
			(hatch none 0.5)
			(connect_pads
				(clearance 0)
			)
			(min_thickness 0.25)
			(keepout
				(tracks not_allowed)
				(vias allowed)
				(pads allowed)
				(copperpour not_allowed)
				(footprints allowed)
			)
			(placement
				(enabled no)
				(sheetname "")
			)
			(fill
				(thermal_gap 0.5)
				(thermal_bridge_width 0.5)
				(island_removal_mode 0)
			)
			(polygon
				(pts
					(xy 191.643 -22.761194) (xy 192.151 -22.761194) (xy 192.151 -23.142194) (xy 191.643 -23.142194)
				)
			)
		)
	)
)
